(kicad_pcb
	(version 20260206)
	(generator "pcbnew")
	(generator_version "10.0")
	(general
		(thickness 1.6)
		(legacy_teardrops no)
	)
	(paper "A4")
	(title_block
		(title "peb — Lightning_PEB_BRD.brd")
		(comment 1 "Lightning (Wiwynn / Facebook NVMe JBOF) / footprints 1863-1870 of 2563")
	)
	(layers
		(0 "F.Cu" signal "TOP")
		(4 "In1.Cu" signal "L2GND")
		(6 "In2.Cu" signal "L3")
		(8 "In3.Cu" signal "L4VCC")
		(10 "In4.Cu" signal "L5VCC")
		(12 "In5.Cu" signal "L6")
		(14 "In6.Cu" signal "L7GND")
		(2 "B.Cu" signal "BOTTOM")
		(9 "F.Adhes" user "F.Adhesive")
		(11 "B.Adhes" user "B.Adhesive")
		(13 "F.Paste" user "Package Geometry/Pastemask Top")
		(15 "B.Paste" user "Package Geometry/Pastemask Bottom")
		(5 "F.SilkS" user "Ref Des/Silkscreen Top")
		(7 "B.SilkS" user "Ref Des/Silkscreen Bottom")
		(1 "F.Mask" user "Board Geometry/Soldermask Top")
		(3 "B.Mask" user "Board Geometry/Soldermask Bottom")
		(17 "Dwgs.User" user "User.Drawings")
		(19 "Cmts.User" user "User.Comments")
		(21 "Eco1.User" user "User.Eco1")
		(23 "Eco2.User" user "User.Eco2")
		(25 "Edge.Cuts" user "Board Geometry/Outline")
		(27 "Margin" user)
		(31 "F.CrtYd" user "Package Geometry/Place Bound Top")
		(29 "B.CrtYd" user "Package Geometry/Place Bound Bottom")
		(35 "F.Fab" user "Ref Des/Assembly Top")
		(33 "B.Fab" user "Ref Des/Assembly Bottom")
	)
	(footprint ""
		(layer "B.Cu")
		(at 270.63065 -12.845542 180)
		(property "Reference" "R722"
			(at 0 0 0)
			(layer "B.SilkS")
			(hide yes)
			(effects
				(font
					(size 1.27 1.27)
				)
				(justify mirror)
			)
		)
		(property "Value" "0R2J-2-GP"
			(at -0.064008 -3.993896 180)
			(unlocked yes)
			(layer "B.Fab")
			(hide yes)
			(effects
				(font
					(size 1.016 1.016)
					(thickness 0.1524)
				)
				(justify mirror)
			)
		)
		(property "Device Type" "R402H16"
			(at -0.064008 -5.517896 180)
			(unlocked yes)
			(layer "B.Fab")
			(hide yes)
			(effects
				(font
					(size 1.016 1.016)
					(thickness 0.1524)
				)
				(justify mirror)
			)
		)
		(duplicate_pad_numbers_are_jumpers no)
		(fp_line
			(start 0.508 -0.9398)
			(end 0.508 0.9398)
			(stroke
				(width 0.1524)
				(type default)
			)
			(layer "B.SilkS")
		)
		(fp_line
			(start -0.508 -0.9398)
			(end 0.508 -0.9398)
			(stroke
				(width 0.1524)
				(type default)
			)
			(layer "B.SilkS")
		)
		(fp_rect
			(start 0.508 0.9398)
			(end -0.508 -0.9398)
			(stroke
				(width 0)
				(type default)
			)
			(fill no)
			(layer "B.CrtYd")
		)
		(fp_rect
			(start 0.508 0.9398)
			(end -0.508 -0.9398)
			(stroke
				(width 0)
				(type default)
			)
			(fill no)
			(layer "B.Fab")
		)
		(pad "1" smd custom
			(at 0 -0.4445)
			(size 0.1397 0.1397)
			(layers "B.Cu" "B.Mask" "B.Paste")
			(net "HOST5_RST_N_C")
			(options
				(clearance outline)
				(anchor circle)
			)
			(primitives
				(gr_poly
					(pts
						(arc
							(start -0.1778 0.2794)
							(mid -0.249642 0.249642)
							(end -0.2794 0.1778)
						)
						(arc
							(start -0.2794 -0.1778)
							(mid -0.249642 -0.249642)
							(end -0.1778 -0.2794)
						)
						(arc
							(start 0.1778 -0.2794)
							(mid 0.249642 -0.249642)
							(end 0.2794 -0.1778)
						)
						(arc
							(start 0.2794 0.1778)
							(mid 0.249642 0.249642)
							(end 0.1778 0.2794)
						)
					)
					(width 0)
					(fill yes)
				)
			)
		)
		(pad "2" smd custom
			(at 0 0.4445)
			(size 0.1397 0.1397)
			(layers "B.Cu" "B.Mask" "B.Paste")
			(net "P3V3_STBY")
			(options
				(clearance outline)
				(anchor circle)
			)
			(primitives
				(gr_poly
					(pts
						(arc
							(start -0.1778 0.2794)
							(mid -0.249642 0.249642)
							(end -0.2794 0.1778)
						)
						(arc
							(start -0.2794 -0.1778)
							(mid -0.249642 -0.249642)
							(end -0.1778 -0.2794)
						)
						(arc
							(start 0.1778 -0.2794)
							(mid 0.249642 -0.249642)
							(end 0.2794 -0.1778)
						)
						(arc
							(start 0.2794 0.1778)
							(mid 0.249642 0.249642)
							(end 0.1778 0.2794)
						)
					)
					(width 0)
					(fill yes)
				)
			)
		)
	)
	(footprint ""
		(layer "B.Cu")
		(at 22.240494 -81.667858 180)
		(property "Reference" "C640"
			(at 0 0 0)
			(layer "B.SilkS")
			(hide yes)
			(effects
				(font
					(size 1.27 1.27)
				)
				(justify mirror)
			)
		)
		(property "Value" "SC10U6D3V5KX-4GP"
			(at 0.0762 -6.1214 180)
			(unlocked yes)
			(layer "B.Fab")
			(hide yes)
			(effects
				(font
					(size 1.016 1.016)
					(thickness 0.1524)
				)
				(justify mirror)
			)
		)
		(property "Device Type" "C805H58"
			(at 0.0762 -8.1534 180)
			(unlocked yes)
			(layer "B.Fab")
			(hide yes)
			(effects
				(font
					(size 1.016 1.016)
					(thickness 0.1524)
				)
				(justify mirror)
			)
		)
		(duplicate_pad_numbers_are_jumpers no)
		(fp_line
			(start -0.635 0)
			(end 0.635 0)
			(stroke
				(width 0.508)
				(type default)
			)
			(layer "B.SilkS")
		)
		(fp_rect
			(start 0.9652 1.778)
			(end -0.9652 -1.778)
			(stroke
				(width 0)
				(type default)
			)
			(fill no)
			(layer "B.CrtYd")
		)
		(fp_poly
			(pts
				(xy 0.9652 -1.778) (xy -0.9652 -1.778) (xy -0.9652 1.778) (xy 0.9652 1.778)
			)
			(stroke
				(width 0)
				(type default)
			)
			(fill no)
			(layer "B.Fab")
		)
		(pad "1" smd rect
			(at 0 -0.9652)
			(size 1.397 1.143)
			(layers "B.Cu" "B.Mask" "B.Paste")
			(net "P0V9_I210")
		)
		(pad "2" smd rect
			(at 0 0.9652)
			(size 1.397 1.143)
			(layers "B.Cu" "B.Mask" "B.Paste")
			(net "GND")
		)
	)
	(footprint ""
		(layer "B.Cu")
		(at 23.796498 -128.037336 90)
		(property "Reference" "R364"
			(at 0 0 90)
			(layer "B.SilkS")
			(hide yes)
			(effects
				(font
					(size 1.27 1.27)
				)
				(justify mirror)
			)
		)
		(property "Value" "3K3R2F-2-GP"
			(at -0.064008 -3.993896 90)
			(unlocked yes)
			(layer "B.Fab")
			(hide yes)
			(effects
				(font
					(size 1.016 1.016)
					(thickness 0.1524)
				)
				(justify mirror)
			)
		)
		(property "Device Type" "R402H16"
			(at -0.064008 -5.517896 90)
			(unlocked yes)
			(layer "B.Fab")
			(hide yes)
			(effects
				(font
					(size 1.016 1.016)
					(thickness 0.1524)
				)
				(justify mirror)
			)
		)
		(duplicate_pad_numbers_are_jumpers no)
		(fp_line
			(start 0.508 -0.9398)
			(end 0.508 0.9398)
			(stroke
				(width 0.1524)
				(type default)
			)
			(layer "B.SilkS")
		)
		(fp_line
			(start -0.508 -0.9398)
			(end 0.508 -0.9398)
			(stroke
				(width 0.1524)
				(type default)
			)
			(layer "B.SilkS")
		)
		(fp_rect
			(start 0.508 0.9398)
			(end -0.508 -0.9398)
			(stroke
				(width 0)
				(type default)
			)
			(fill no)
			(layer "B.CrtYd")
		)
		(fp_rect
			(start 0.508 0.9398)
			(end -0.508 -0.9398)
			(stroke
				(width 0)
				(type default)
			)
			(fill no)
			(layer "B.Fab")
		)
		(pad "1" smd custom
			(at 0 -0.4445 270)
			(size 0.1397 0.1397)
			(layers "B.Cu" "B.Mask" "B.Paste")
			(net "P3V3_STBY")
			(options
				(clearance outline)
				(anchor circle)
			)
			(primitives
				(gr_poly
					(pts
						(arc
							(start -0.1778 0.2794)
							(mid -0.249642 0.249642)
							(end -0.2794 0.1778)
						)
						(arc
							(start -0.2794 -0.1778)
							(mid -0.249642 -0.249642)
							(end -0.1778 -0.2794)
						)
						(arc
							(start 0.1778 -0.2794)
							(mid 0.249642 -0.249642)
							(end 0.2794 -0.1778)
						)
						(arc
							(start 0.2794 0.1778)
							(mid 0.249642 0.249642)
							(end 0.1778 0.2794)
						)
					)
					(width 0)
					(fill yes)
				)
			)
		)
		(pad "2" smd custom
			(at 0 0.4445 270)
			(size 0.1397 0.1397)
			(layers "B.Cu" "B.Mask" "B.Paste")
			(net "ROMA14")
			(options
				(clearance outline)
				(anchor circle)
			)
			(primitives
				(gr_poly
					(pts
						(arc
							(start -0.1778 0.2794)
							(mid -0.249642 0.249642)
							(end -0.2794 0.1778)
						)
						(arc
							(start -0.2794 -0.1778)
							(mid -0.249642 -0.249642)
							(end -0.1778 -0.2794)
						)
						(arc
							(start 0.1778 -0.2794)
							(mid 0.249642 -0.249642)
							(end 0.2794 -0.1778)
						)
						(arc
							(start 0.2794 0.1778)
							(mid 0.249642 0.249642)
							(end 0.1778 0.2794)
						)
					)
					(width 0)
					(fill yes)
				)
			)
		)
	)
	(footprint ""
		(layer "B.Cu")
		(at 252.603 -59.9948 -90)
		(property "Reference" "C578"
			(at 0 0 90)
			(layer "B.SilkS")
			(hide yes)
			(effects
				(font
					(size 1.27 1.27)
				)
				(justify mirror)
			)
		)
		(property "Value" "SCD1U16V1KX-1-GP"
			(at 2.8321 -1.7399 270)
			(unlocked yes)
			(layer "B.Fab")
			(hide yes)
			(effects
				(font
					(size 1.016 1.016)
					(thickness 0.1524)
				)
				(justify mirror)
			)
		)
		(property "Device Type" "C0201H13"
			(at 2.8321 -3.2639 270)
			(unlocked yes)
			(layer "B.Fab")
			(hide yes)
			(effects
				(font
					(size 1.016 1.016)
					(thickness 0.1524)
				)
				(justify mirror)
			)
		)
		(duplicate_pad_numbers_are_jumpers no)
		(fp_rect
			(start 0.2794 0.6477)
			(end -0.2794 -0.6477)
			(stroke
				(width 0)
				(type default)
			)
			(fill no)
			(layer "B.CrtYd")
		)
		(fp_rect
			(start 0.2794 0.6477)
			(end -0.2794 -0.6477)
			(stroke
				(width 0)
				(type default)
			)
			(fill no)
			(layer "B.Fab")
		)
		(pad "1" smd custom
			(at 0 -0.2794 90)
			(size 0.0762 0.0762)
			(layers "B.Cu" "B.Mask" "B.Paste")
			(net "DUT_AVD_PCIE")
			(options
				(clearance outline)
				(anchor circle)
			)
			(primitives
				(gr_poly
					(pts
						(arc
							(start 0.1524 0.127)
							(mid 0.137521 0.162921)
							(end 0.1016 0.1778)
						)
						(arc
							(start -0.1016 0.1778)
							(mid -0.137521 0.162921)
							(end -0.1524 0.127)
						)
						(arc
							(start -0.1524 -0.127)
							(mid -0.137521 -0.162921)
							(end -0.1016 -0.1778)
						)
						(arc
							(start 0.1016 -0.1778)
							(mid 0.137521 -0.162921)
							(end 0.1524 -0.127)
						)
					)
					(width 0)
					(fill yes)
				)
			)
		)
		(pad "2" smd custom
			(at 0 0.2794 90)
			(size 0.0762 0.0762)
			(layers "B.Cu" "B.Mask" "B.Paste")
			(net "GND")
			(options
				(clearance outline)
				(anchor circle)
			)
			(primitives
				(gr_poly
					(pts
						(arc
							(start 0.1524 0.127)
							(mid 0.137521 0.162921)
							(end 0.1016 0.1778)
						)
						(arc
							(start -0.1016 0.1778)
							(mid -0.137521 0.162921)
							(end -0.1524 0.127)
						)
						(arc
							(start -0.1524 -0.127)
							(mid -0.137521 -0.162921)
							(end -0.1016 -0.1778)
						)
						(arc
							(start 0.1016 -0.1778)
							(mid 0.137521 -0.162921)
							(end 0.1524 -0.127)
						)
					)
					(width 0)
					(fill yes)
				)
			)
		)
	)
	(footprint ""
		(layer "B.Cu")
		(at 20.955 -137.795 -90)
		(property "Reference" "R636"
			(at 0 0 90)
			(layer "B.SilkS")
			(hide yes)
			(effects
				(font
					(size 1.27 1.27)
				)
				(justify mirror)
			)
		)
		(property "Value" "0R2J-2-GP"
			(at -0.064008 -3.993896 270)
			(unlocked yes)
			(layer "B.Fab")
			(hide yes)
			(effects
				(font
					(size 1.016 1.016)
					(thickness 0.1524)
				)
				(justify mirror)
			)
		)
		(property "Device Type" "R402H16"
			(at -0.064008 -5.517896 270)
			(unlocked yes)
			(layer "B.Fab")
			(hide yes)
			(effects
				(font
					(size 1.016 1.016)
					(thickness 0.1524)
				)
				(justify mirror)
			)
		)
		(duplicate_pad_numbers_are_jumpers no)
		(fp_line
			(start -0.508 -0.9398)
			(end 0.508 -0.9398)
			(stroke
				(width 0.1524)
				(type default)
			)
			(layer "B.SilkS")
		)
		(fp_line
			(start 0.508 -0.9398)
			(end 0.508 0.9398)
			(stroke
				(width 0.1524)
				(type default)
			)
			(layer "B.SilkS")
		)
		(fp_rect
			(start 0.508 0.9398)
			(end -0.508 -0.9398)
			(stroke
				(width 0)
				(type default)
			)
			(fill no)
			(layer "B.CrtYd")
		)
		(fp_rect
			(start 0.508 0.9398)
			(end -0.508 -0.9398)
			(stroke
				(width 0)
				(type default)
			)
			(fill no)
			(layer "B.Fab")
		)
		(pad "1" smd custom
			(at 0 -0.4445 90)
			(size 0.1397 0.1397)
			(layers "B.Cu" "B.Mask" "B.Paste")
			(net "ROMD2")
			(options
				(clearance outline)
				(anchor circle)
			)
			(primitives
				(gr_poly
					(pts
						(arc
							(start -0.1778 0.2794)
							(mid -0.249642 0.249642)
							(end -0.2794 0.1778)
						)
						(arc
							(start -0.2794 -0.1778)
							(mid -0.249642 -0.249642)
							(end -0.1778 -0.2794)
						)
						(arc
							(start 0.1778 -0.2794)
							(mid 0.249642 -0.249642)
							(end 0.2794 -0.1778)
						)
						(arc
							(start 0.2794 0.1778)
							(mid 0.249642 0.249642)
							(end 0.1778 0.2794)
						)
					)
					(width 0)
					(fill yes)
				)
			)
		)
		(pad "2" smd custom
			(at 0 0.4445 90)
			(size 0.1397 0.1397)
			(layers "B.Cu" "B.Mask" "B.Paste")
			(net "ROMD2_R")
			(options
				(clearance outline)
				(anchor circle)
			)
			(primitives
				(gr_poly
					(pts
						(arc
							(start -0.1778 0.2794)
							(mid -0.249642 0.249642)
							(end -0.2794 0.1778)
						)
						(arc
							(start -0.2794 -0.1778)
							(mid -0.249642 -0.249642)
							(end -0.1778 -0.2794)
						)
						(arc
							(start 0.1778 -0.2794)
							(mid 0.249642 -0.249642)
							(end 0.2794 -0.1778)
						)
						(arc
							(start 0.2794 0.1778)
							(mid 0.249642 0.249642)
							(end 0.1778 0.2794)
						)
					)
					(width 0)
					(fill yes)
				)
			)
		)
	)
	(footprint ""
		(layer "B.Cu")
		(at 208.333848 -4.043426)
		(property "Reference" "R3711"
			(at 0 0 0)
			(layer "B.SilkS")
			(hide yes)
			(effects
				(font
					(size 1.27 1.27)
				)
				(justify mirror)
			)
		)
		(property "Value" "1KR2F-3-GP"
			(at -0.064008 -3.993896 0)
			(unlocked yes)
			(layer "B.Fab")
			(hide yes)
			(effects
				(font
					(size 1.016 1.016)
					(thickness 0.1524)
				)
				(justify mirror)
			)
		)
		(property "Device Type" "R402H16"
			(at -0.064008 -5.517896 0)
			(unlocked yes)
			(layer "B.Fab")
			(hide yes)
			(effects
				(font
					(size 1.016 1.016)
					(thickness 0.1524)
				)
				(justify mirror)
			)
		)
		(duplicate_pad_numbers_are_jumpers no)
		(fp_line
			(start -0.508 -0.9398)
			(end 0.508 -0.9398)
			(stroke
				(width 0.1524)
				(type default)
			)
			(layer "B.SilkS")
		)
		(fp_line
			(start 0.508 -0.9398)
			(end 0.508 0.9398)
			(stroke
				(width 0.1524)
				(type default)
			)
			(layer "B.SilkS")
		)
		(fp_rect
			(start 0.508 0.9398)
			(end -0.508 -0.9398)
			(stroke
				(width 0)
				(type default)
			)
			(fill no)
			(layer "B.CrtYd")
		)
		(fp_rect
			(start 0.508 0.9398)
			(end -0.508 -0.9398)
			(stroke
				(width 0)
				(type default)
			)
			(fill no)
			(layer "B.Fab")
		)
		(pad "1" smd custom
			(at 0 -0.4445 180)
			(size 0.1397 0.1397)
			(layers "B.Cu" "B.Mask" "B.Paste")
			(net "HOST8_RST_N")
			(options
				(clearance outline)
				(anchor circle)
			)
			(primitives
				(gr_poly
					(pts
						(arc
							(start -0.1778 0.2794)
							(mid -0.249642 0.249642)
							(end -0.2794 0.1778)
						)
						(arc
							(start -0.2794 -0.1778)
							(mid -0.249642 -0.249642)
							(end -0.1778 -0.2794)
						)
						(arc
							(start 0.1778 -0.2794)
							(mid 0.249642 -0.249642)
							(end 0.2794 -0.1778)
						)
						(arc
							(start 0.2794 0.1778)
							(mid 0.249642 0.249642)
							(end 0.1778 0.2794)
						)
					)
					(width 0)
					(fill yes)
				)
			)
		)
		(pad "2" smd custom
			(at 0 0.4445 180)
			(size 0.1397 0.1397)
			(layers "B.Cu" "B.Mask" "B.Paste")
			(net "P3V3_STBY")
			(options
				(clearance outline)
				(anchor circle)
			)
			(primitives
				(gr_poly
					(pts
						(arc
							(start -0.1778 0.2794)
							(mid -0.249642 0.249642)
							(end -0.2794 0.1778)
						)
						(arc
							(start -0.2794 -0.1778)
							(mid -0.249642 -0.249642)
							(end -0.1778 -0.2794)
						)
						(arc
							(start 0.1778 -0.2794)
							(mid 0.249642 -0.249642)
							(end 0.2794 -0.1778)
						)
						(arc
							(start 0.2794 0.1778)
							(mid 0.249642 0.249642)
							(end 0.1778 0.2794)
						)
					)
					(width 0)
					(fill yes)
				)
			)
		)
	)
	(footprint ""
		(layer "B.Cu")
		(at 248.59996 -40.999918 180)
		(property "Reference" "TP206"
			(at 0 0 0)
			(layer "B.SilkS")
			(hide yes)
			(effects
				(font
					(size 1.27 1.27)
				)
				(justify mirror)
			)
		)
		(property "Value" "TPAD28-2-GP"
			(at 0.0127 -1.6637 180)
			(unlocked yes)
			(layer "B.Fab")
			(hide yes)
			(effects
				(font
					(size 1.016 1.016)
					(thickness 0.1524)
				)
				(justify mirror)
			)
		)
		(property "Device Type" "TPAD28"
			(at 0.0127 -3.1877 180)
			(unlocked yes)
			(layer "B.Fab")
			(hide yes)
			(effects
				(font
					(size 1.016 1.016)
					(thickness 0.1524)
				)
				(justify mirror)
			)
		)
		(duplicate_pad_numbers_are_jumpers no)
		(fp_poly
			(pts
				(arc
					(start -0.3556 0)
					(mid 0.3556 0)
					(end -0.3556 0)
				)
			)
			(stroke
				(width 0)
				(type default)
			)
			(fill no)
			(layer "B.CrtYd")
		)
		(fp_poly
			(pts
				(arc
					(start -0.6096 0)
					(mid 0.6096 0)
					(end -0.6096 0)
				)
			)
			(stroke
				(width 0)
				(type default)
			)
			(fill no)
			(layer "B.Fab")
		)
		(pad "1" smd circle
			(at 0 0)
			(size 0.7112 0.7112)
			(layers "B.Cu" "B.Mask" "B.Paste")
			(net "GPIO107_R")
		)
	)
	(footprint ""
		(layer "B.Cu")
		(at 230.251 -23.241 180)
		(property "Reference" "R825"
			(at 0 0 0)
			(layer "B.SilkS")
			(hide yes)
			(effects
				(font
					(size 1.27 1.27)
				)
				(justify mirror)
			)
		)
		(property "Value" "0R2J-2-GP"
			(at -0.064008 -3.993896 180)
			(unlocked yes)
			(layer "B.Fab")
			(hide yes)
			(effects
				(font
					(size 1.016 1.016)
					(thickness 0.1524)
				)
				(justify mirror)
			)
		)
		(property "Device Type" "R402H16"
			(at -0.064008 -5.517896 180)
			(unlocked yes)
			(layer "B.Fab")
			(hide yes)
			(effects
				(font
					(size 1.016 1.016)
					(thickness 0.1524)
				)
				(justify mirror)
			)
		)
		(duplicate_pad_numbers_are_jumpers no)
		(fp_line
			(start 0.508 -0.9398)
			(end 0.508 0.9398)
			(stroke
				(width 0.1524)
				(type default)
			)
			(layer "B.SilkS")
		)
		(fp_line
			(start -0.508 -0.9398)
			(end 0.508 -0.9398)
			(stroke
				(width 0.1524)
				(type default)
			)
			(layer "B.SilkS")
		)
		(fp_rect
			(start 0.508 0.9398)
			(end -0.508 -0.9398)
			(stroke
				(width 0)
				(type default)
			)
			(fill no)
			(layer "B.CrtYd")
		)
		(fp_rect
			(start 0.508 0.9398)
			(end -0.508 -0.9398)
			(stroke
				(width 0)
				(type default)
			)
			(fill no)
			(layer "B.Fab")
		)
		(pad "1" smd custom
			(at 0 -0.4445)
			(size 0.1397 0.1397)
			(layers "B.Cu" "B.Mask" "B.Paste")
			(net "HOST1_RST_N_LS")
			(options
				(clearance outline)
				(anchor circle)
			)
			(primitives
				(gr_poly
					(pts
						(arc
							(start -0.1778 0.2794)
							(mid -0.249642 0.249642)
							(end -0.2794 0.1778)
						)
						(arc
							(start -0.2794 -0.1778)
							(mid -0.249642 -0.249642)
							(end -0.1778 -0.2794)
						)
						(arc
							(start 0.1778 -0.2794)
							(mid 0.249642 -0.249642)
							(end 0.2794 -0.1778)
						)
						(arc
							(start 0.2794 0.1778)
							(mid 0.249642 0.249642)
							(end 0.1778 0.2794)
						)
					)
					(width 0)
					(fill yes)
				)
			)
		)
		(pad "2" smd custom
			(at 0 0.4445)
			(size 0.1397 0.1397)
			(layers "B.Cu" "B.Mask" "B.Paste")
			(net "LBI_ADDR_0_R")
			(options
				(clearance outline)
				(anchor circle)
			)
			(primitives
				(gr_poly
					(pts
						(arc
							(start -0.1778 0.2794)
							(mid -0.249642 0.249642)
							(end -0.2794 0.1778)
						)
						(arc
							(start -0.2794 -0.1778)
							(mid -0.249642 -0.249642)
							(end -0.1778 -0.2794)
						)
						(arc
							(start 0.1778 -0.2794)
							(mid 0.249642 -0.249642)
							(end 0.2794 -0.1778)
						)
						(arc
							(start 0.2794 0.1778)
							(mid 0.249642 0.249642)
							(end 0.1778 0.2794)
						)
					)
					(width 0)
					(fill yes)
				)
			)
		)
	)
)
